(kicad_pcb
	(version 20260206)
	(generator "pcbnew")
	(generator_version "10.0")
	(general
		(thickness 1.6)
		(legacy_teardrops no)
	)
	(paper "A4")
	(title_block
		(title "03242023_DA0F0TMBIJ0_F0T_Motherboard_J_brd_V01_OCP.brd")
		(comment 1 "Grand Teton / footprints 1169-1175 of 6105")
	)
	(layers
		(0 "F.Cu" signal "TOP")
		(4 "In1.Cu" signal "GND")
		(6 "In2.Cu" signal "IN1")
		(8 "In3.Cu" signal "GND1")
		(10 "In4.Cu" signal "IN2")
		(12 "In5.Cu" signal "GND2")
		(14 "In6.Cu" signal "IN3")
		(16 "In7.Cu" signal "GND3")
		(18 "In8.Cu" signal "VCC")
		(20 "In9.Cu" signal "VCC1")
		(22 "In10.Cu" signal "GND4")
		(24 "In11.Cu" signal "IN4")
		(26 "In12.Cu" signal "GND5")
		(28 "In13.Cu" signal "IN5")
		(30 "In14.Cu" signal "GND6")
		(32 "In15.Cu" signal "IN6")
		(34 "In16.Cu" signal "GND7")
		(2 "B.Cu" signal "BOTTOM")
		(9 "F.Adhes" user "F.Adhesive")
		(11 "B.Adhes" user "B.Adhesive")
		(13 "F.Paste" user "Package Geometry/Pastemask Top")
		(15 "B.Paste" user "Package Geometry/Pastemask Bottom")
		(5 "F.SilkS" user "Ref Des/Silkscreen Top")
		(7 "B.SilkS" user "Ref Des/Silkscreen Bottom")
		(1 "F.Mask" user "Board Geometry/Soldermask Top")
		(3 "B.Mask" user "Board Geometry/Soldermask Bottom")
		(17 "Dwgs.User" user "User.Drawings")
		(19 "Cmts.User" user "User.Comments")
		(21 "Eco1.User" user "User.Eco1")
		(23 "Eco2.User" user "User.Eco2")
		(25 "Edge.Cuts" user "Board Geometry/Outline")
		(27 "Margin" user)
		(31 "F.CrtYd" user "Package Geometry/Place Bound Top")
		(29 "B.CrtYd" user "Package Geometry/Place Bound Bottom")
		(35 "F.Fab" user "Ref Des/Assembly Top")
		(33 "B.Fab" user "Ref Des/Assembly Bottom")
	)
	(footprint ""
		(layer "F.Cu")
		(at 248.20753 -52.177442 90)
		(property "Reference" "PR3950"
			(at 0 0 90)
			(layer "F.SilkS")
			(hide yes)
			(effects
				(font
					(size 1.27 1.27)
				)
			)
		)
		(property "Value" ""
			(at 0 0 90)
			(layer "F.Fab")
			(effects
				(font
					(size 1.27 1.27)
				)
			)
		)
		(duplicate_pad_numbers_are_jumpers no)
		(fp_line
			(start 0.7874 -0.4064)
			(end 0.7874 0.4064)
			(stroke
				(width 0.1524)
				(type default)
			)
			(layer "F.SilkS")
		)
		(fp_line
			(start -0.7874 -0.4064)
			(end 0.7874 -0.4064)
			(stroke
				(width 0.1524)
				(type default)
			)
			(layer "F.SilkS")
		)
		(fp_line
			(start 0.7874 0.4064)
			(end -0.7874 0.4064)
			(stroke
				(width 0.1524)
				(type default)
			)
			(layer "F.SilkS")
		)
		(fp_line
			(start -0.7874 0.4064)
			(end -0.7874 -0.4064)
			(stroke
				(width 0.1524)
				(type default)
			)
			(layer "F.SilkS")
		)
		(fp_line
			(start -0.12065 -0.305054)
			(end -0.12065 -0.2794)
			(stroke
				(width 0.1)
				(type default)
			)
			(layer "F.Fab")
		)
		(fp_line
			(start -0.67945 -0.305054)
			(end -0.12065 -0.305054)
			(stroke
				(width 0.1)
				(type default)
			)
			(layer "F.Fab")
		)
		(fp_line
			(start 0.67945 -0.3048)
			(end 0.67945 0.3048)
			(stroke
				(width 0.1)
				(type default)
			)
			(layer "F.Fab")
		)
		(fp_line
			(start 0.12065 -0.3048)
			(end 0.67945 -0.3048)
			(stroke
				(width 0.1)
				(type default)
			)
			(layer "F.Fab")
		)
		(fp_line
			(start 0.12065 -0.2794)
			(end 0.12065 -0.3048)
			(stroke
				(width 0.1)
				(type default)
			)
			(layer "F.Fab")
		)
		(fp_line
			(start -0.12065 -0.2794)
			(end 0.12065 -0.2794)
			(stroke
				(width 0.1)
				(type default)
			)
			(layer "F.Fab")
		)
		(fp_line
			(start 0.120396 0.2794)
			(end -0.12065 0.2794)
			(stroke
				(width 0.1)
				(type default)
			)
			(layer "F.Fab")
		)
		(fp_line
			(start -0.12065 0.2794)
			(end -0.12065 0.3048)
			(stroke
				(width 0.1)
				(type default)
			)
			(layer "F.Fab")
		)
		(fp_line
			(start 0.67945 0.3048)
			(end 0.120396 0.3048)
			(stroke
				(width 0.1)
				(type default)
			)
			(layer "F.Fab")
		)
		(fp_line
			(start 0.120396 0.3048)
			(end 0.120396 0.2794)
			(stroke
				(width 0.1)
				(type default)
			)
			(layer "F.Fab")
		)
		(fp_line
			(start -0.12065 0.3048)
			(end -0.67945 0.3048)
			(stroke
				(width 0.1)
				(type default)
			)
			(layer "F.Fab")
		)
		(fp_line
			(start -0.67945 0.3048)
			(end -0.67945 -0.305054)
			(stroke
				(width 0.1)
				(type default)
			)
			(layer "F.Fab")
		)
		(pad "1" smd circle
			(at -0.40005 0 90)
			(size 0 0)
			(layers "F.Cu" "F.Mask" "F.Paste")
			(net "P12V_E1S_0")
		)
		(pad "2" smd circle
			(at 0.40005 0 90)
			(size 0 0)
			(layers "F.Cu" "F.Mask" "F.Paste")
			(net "P12V_E1S_AVIN_PD_0")
		)
	)
	(footprint ""
		(layer "F.Cu")
		(at 173.597062 -32.935672 90)
		(property "Reference" "PR4005"
			(at 0 0 90)
			(layer "F.SilkS")
			(hide yes)
			(effects
				(font
					(size 1.27 1.27)
				)
			)
		)
		(property "Value" ""
			(at 0 0 90)
			(layer "F.Fab")
			(effects
				(font
					(size 1.27 1.27)
				)
			)
		)
		(duplicate_pad_numbers_are_jumpers no)
		(fp_line
			(start 0.7874 -0.4064)
			(end 0.7874 0.4064)
			(stroke
				(width 0.1524)
				(type default)
			)
			(layer "F.SilkS")
		)
		(fp_line
			(start -0.7874 -0.4064)
			(end 0.7874 -0.4064)
			(stroke
				(width 0.1524)
				(type default)
			)
			(layer "F.SilkS")
		)
		(fp_line
			(start 0.7874 0.4064)
			(end -0.7874 0.4064)
			(stroke
				(width 0.1524)
				(type default)
			)
			(layer "F.SilkS")
		)
		(fp_line
			(start -0.7874 0.4064)
			(end -0.7874 -0.4064)
			(stroke
				(width 0.1524)
				(type default)
			)
			(layer "F.SilkS")
		)
		(fp_line
			(start -0.12065 -0.305054)
			(end -0.12065 -0.2794)
			(stroke
				(width 0.1)
				(type default)
			)
			(layer "F.Fab")
		)
		(fp_line
			(start -0.67945 -0.305054)
			(end -0.12065 -0.305054)
			(stroke
				(width 0.1)
				(type default)
			)
			(layer "F.Fab")
		)
		(fp_line
			(start 0.67945 -0.3048)
			(end 0.67945 0.3048)
			(stroke
				(width 0.1)
				(type default)
			)
			(layer "F.Fab")
		)
		(fp_line
			(start 0.12065 -0.3048)
			(end 0.67945 -0.3048)
			(stroke
				(width 0.1)
				(type default)
			)
			(layer "F.Fab")
		)
		(fp_line
			(start 0.12065 -0.2794)
			(end 0.12065 -0.3048)
			(stroke
				(width 0.1)
				(type default)
			)
			(layer "F.Fab")
		)
		(fp_line
			(start -0.12065 -0.2794)
			(end 0.12065 -0.2794)
			(stroke
				(width 0.1)
				(type default)
			)
			(layer "F.Fab")
		)
		(fp_line
			(start 0.120396 0.2794)
			(end -0.12065 0.2794)
			(stroke
				(width 0.1)
				(type default)
			)
			(layer "F.Fab")
		)
		(fp_line
			(start -0.12065 0.2794)
			(end -0.12065 0.3048)
			(stroke
				(width 0.1)
				(type default)
			)
			(layer "F.Fab")
		)
		(fp_line
			(start 0.67945 0.3048)
			(end 0.120396 0.3048)
			(stroke
				(width 0.1)
				(type default)
			)
			(layer "F.Fab")
		)
		(fp_line
			(start 0.120396 0.3048)
			(end 0.120396 0.2794)
			(stroke
				(width 0.1)
				(type default)
			)
			(layer "F.Fab")
		)
		(fp_line
			(start -0.12065 0.3048)
			(end -0.67945 0.3048)
			(stroke
				(width 0.1)
				(type default)
			)
			(layer "F.Fab")
		)
		(fp_line
			(start -0.67945 0.3048)
			(end -0.67945 -0.305054)
			(stroke
				(width 0.1)
				(type default)
			)
			(layer "F.Fab")
		)
		(pad "1" smd circle
			(at -0.40005 0 90)
			(size 0 0)
			(layers "F.Cu" "F.Mask" "F.Paste")
			(net "P12V_SCM_IMON")
		)
		(pad "2" smd circle
			(at 0.40005 0 90)
			(size 0 0)
			(layers "F.Cu" "F.Mask" "F.Paste")
			(net "GND")
		)
	)
	(footprint ""
		(layer "F.Cu")
		(at 415.4678 -17.612614 90)
		(property "Reference" "C856"
			(at 0 0 90)
			(layer "F.SilkS")
			(hide yes)
			(effects
				(font
					(size 1.27 1.27)
				)
			)
		)
		(property "Value" ""
			(at 0 0 90)
			(layer "F.Fab")
			(effects
				(font
					(size 1.27 1.27)
				)
			)
		)
		(duplicate_pad_numbers_are_jumpers no)
		(fp_line
			(start 0.299974 -0.150114)
			(end 0.299974 0.150114)
			(stroke
				(width 0.1)
				(type default)
			)
			(layer "F.Fab")
		)
		(fp_line
			(start -0.299974 -0.150114)
			(end 0.299974 -0.150114)
			(stroke
				(width 0.1)
				(type default)
			)
			(layer "F.Fab")
		)
		(fp_line
			(start 0.299974 0.150114)
			(end -0.299974 0.150114)
			(stroke
				(width 0.1)
				(type default)
			)
			(layer "F.Fab")
		)
		(fp_line
			(start -0.299974 0.150114)
			(end -0.299974 -0.150114)
			(stroke
				(width 0.1)
				(type default)
			)
			(layer "F.Fab")
		)
		(pad "1" smd rect
			(at -0.2667 0 90)
			(size 0.3048 0.381)
			(layers "F.Cu" "F.Mask" "F.Paste")
			(net "P5E_CPU0_PE1_TX_C_DN<6>")
		)
		(pad "2" smd rect
			(at 0.2667 0 90)
			(size 0.3048 0.381)
			(layers "F.Cu" "F.Mask" "F.Paste")
			(net "P5E_CPU0_PE1_TX_DN<6>")
		)
	)
	(footprint ""
		(layer "F.Cu")
		(at 116.367306 -30.720792 180)
		(property "Reference" "R3190"
			(at 0 0 180)
			(layer "F.SilkS")
			(hide yes)
			(effects
				(font
					(size 1.27 1.27)
				)
			)
		)
		(property "Value" ""
			(at 0 0 180)
			(layer "F.Fab")
			(effects
				(font
					(size 1.27 1.27)
				)
			)
		)
		(duplicate_pad_numbers_are_jumpers no)
		(fp_line
			(start 0.7874 0.4064)
			(end -0.7874 0.4064)
			(stroke
				(width 0.1524)
				(type default)
			)
			(layer "F.SilkS")
		)
		(fp_line
			(start 0.7874 -0.4064)
			(end 0.7874 0.4064)
			(stroke
				(width 0.1524)
				(type default)
			)
			(layer "F.SilkS")
		)
		(fp_line
			(start -0.7874 0.4064)
			(end -0.7874 -0.4064)
			(stroke
				(width 0.1524)
				(type default)
			)
			(layer "F.SilkS")
		)
		(fp_line
			(start -0.7874 -0.4064)
			(end 0.7874 -0.4064)
			(stroke
				(width 0.1524)
				(type default)
			)
			(layer "F.SilkS")
		)
		(fp_line
			(start 0.67945 0.3048)
			(end 0.120396 0.3048)
			(stroke
				(width 0.1)
				(type default)
			)
			(layer "F.Fab")
		)
		(fp_line
			(start 0.67945 -0.3048)
			(end 0.67945 0.3048)
			(stroke
				(width 0.1)
				(type default)
			)
			(layer "F.Fab")
		)
		(fp_line
			(start 0.12065 -0.2794)
			(end 0.12065 -0.3048)
			(stroke
				(width 0.1)
				(type default)
			)
			(layer "F.Fab")
		)
		(fp_line
			(start 0.12065 -0.3048)
			(end 0.67945 -0.3048)
			(stroke
				(width 0.1)
				(type default)
			)
			(layer "F.Fab")
		)
		(fp_line
			(start 0.120396 0.3048)
			(end 0.120396 0.2794)
			(stroke
				(width 0.1)
				(type default)
			)
			(layer "F.Fab")
		)
		(fp_line
			(start 0.120396 0.2794)
			(end -0.12065 0.2794)
			(stroke
				(width 0.1)
				(type default)
			)
			(layer "F.Fab")
		)
		(fp_line
			(start -0.12065 0.3048)
			(end -0.67945 0.3048)
			(stroke
				(width 0.1)
				(type default)
			)
			(layer "F.Fab")
		)
		(fp_line
			(start -0.12065 0.2794)
			(end -0.12065 0.3048)
			(stroke
				(width 0.1)
				(type default)
			)
			(layer "F.Fab")
		)
		(fp_line
			(start -0.12065 -0.2794)
			(end 0.12065 -0.2794)
			(stroke
				(width 0.1)
				(type default)
			)
			(layer "F.Fab")
		)
		(fp_line
			(start -0.12065 -0.305054)
			(end -0.12065 -0.2794)
			(stroke
				(width 0.1)
				(type default)
			)
			(layer "F.Fab")
		)
		(fp_line
			(start -0.67945 0.3048)
			(end -0.67945 -0.305054)
			(stroke
				(width 0.1)
				(type default)
			)
			(layer "F.Fab")
		)
		(fp_line
			(start -0.67945 -0.305054)
			(end -0.12065 -0.305054)
			(stroke
				(width 0.1)
				(type default)
			)
			(layer "F.Fab")
		)
		(pad "1" smd circle
			(at -0.40005 0 180)
			(size 0 0)
			(layers "F.Cu" "F.Mask" "F.Paste")
			(net "P3V3_AUX")
		)
		(pad "2" smd circle
			(at 0.40005 0 180)
			(size 0 0)
			(layers "F.Cu" "F.Mask" "F.Paste")
			(net "OCP_V3_2_PWRBRK_BUFF_N")
		)
	)
	(footprint ""
		(layer "F.Cu")
		(at 127.170434 -402.371052 -90)
		(property "Reference" "C746"
			(at 0 0 270)
			(layer "F.SilkS")
			(hide yes)
			(effects
				(font
					(size 1.27 1.27)
				)
			)
		)
		(property "Value" ""
			(at 0 0 270)
			(layer "F.Fab")
			(effects
				(font
					(size 1.27 1.27)
				)
			)
		)
		(duplicate_pad_numbers_are_jumpers no)
		(fp_line
			(start -0.299974 0.150114)
			(end -0.299974 -0.150114)
			(stroke
				(width 0.1)
				(type default)
			)
			(layer "F.Fab")
		)
		(fp_line
			(start 0.299974 0.150114)
			(end -0.299974 0.150114)
			(stroke
				(width 0.1)
				(type default)
			)
			(layer "F.Fab")
		)
		(fp_line
			(start -0.299974 -0.150114)
			(end 0.299974 -0.150114)
			(stroke
				(width 0.1)
				(type default)
			)
			(layer "F.Fab")
		)
		(fp_line
			(start 0.299974 -0.150114)
			(end 0.299974 0.150114)
			(stroke
				(width 0.1)
				(type default)
			)
			(layer "F.Fab")
		)
		(pad "1" smd rect
			(at -0.2667 0 270)
			(size 0.3048 0.381)
			(layers "F.Cu" "F.Mask" "F.Paste")
			(net "P5E_CPU1_PE2_TX_C_DN<13>")
		)
		(pad "2" smd rect
			(at 0.2667 0 270)
			(size 0.3048 0.381)
			(layers "F.Cu" "F.Mask" "F.Paste")
			(net "P5E_CPU1_PE2_TX_DN<13>")
		)
	)
	(footprint ""
		(layer "F.Cu")
		(at 488.03433 -148.048472 90)
		(property "Reference" "X22"
			(at -3.517392 3.52298 90)
			(unlocked yes)
			(layer "F.SilkS")
			(effects
				(font
					(size 0.7874 0.5842)
					(thickness 0.1524)
				)
				(justify left)
			)
		)
		(property "Value" ""
			(at 0 0 90)
			(layer "F.Fab")
			(effects
				(font
					(size 1.27 1.27)
				)
			)
		)
		(property "Device Type" "TP_TDR_4P_FTS_TH-TP_TDR_4P_DIPA"
			(at 1.30175 1.27 180)
			(unlocked yes)
			(layer "F.Fab")
			(hide yes)
			(effects
				(font
					(size 0.635 0.4064)
					(thickness 0.1524)
				)
			)
		)
		(property "User Part Number" "N_A"
			(at 1.30175 1.27 180)
			(unlocked yes)
			(layer "Cmts.User")
			(hide yes)
			(effects
				(font
					(size 0.635 0.4064)
					(thickness 0.1524)
				)
			)
		)
		(duplicate_pad_numbers_are_jumpers no)
		(fp_line
			(start 2.54 -1.27)
			(end 0 -1.27)
			(stroke
				(width 0.1524)
				(type default)
			)
			(layer "F.SilkS")
		)
		(fp_line
			(start 0 -1.27)
			(end 0 -0.635)
			(stroke
				(width 0.1524)
				(type default)
			)
			(layer "F.SilkS")
		)
		(fp_line
			(start 2.54 -1.1303)
			(end 2.54 -1.27)
			(stroke
				(width 0.1524)
				(type default)
			)
			(layer "F.SilkS")
		)
		(fp_line
			(start 0 0.635)
			(end 0 1.905)
			(stroke
				(width 0.1524)
				(type default)
			)
			(layer "F.SilkS")
		)
		(fp_line
			(start 2.54 1.4097)
			(end 2.54 1.1303)
			(stroke
				(width 0.1524)
				(type default)
			)
			(layer "F.SilkS")
		)
		(fp_line
			(start 0 3.175)
			(end 0 3.81)
			(stroke
				(width 0.1524)
				(type default)
			)
			(layer "F.SilkS")
		)
		(fp_line
			(start 2.54 3.81)
			(end 2.54 3.6703)
			(stroke
				(width 0.1524)
				(type default)
			)
			(layer "F.SilkS")
		)
		(fp_line
			(start 0 3.81)
			(end 2.54 3.81)
			(stroke
				(width 0.1524)
				(type default)
			)
			(layer "F.SilkS")
		)
		(fp_poly
			(pts
				(xy -0.761746 0) (xy -2.285746 0.762) (xy -2.285746 -0.762)
			)
			(stroke
				(width 0)
				(type default)
			)
			(fill yes)
			(layer "F.SilkS")
		)
		(fp_line
			(start 2.54 -1.27)
			(end 0 -1.27)
			(stroke
				(width 0.1)
				(type default)
			)
			(layer "F.Fab")
		)
		(fp_line
			(start 0 -1.27)
			(end 0 3.81)
			(stroke
				(width 0.1)
				(type default)
			)
			(layer "F.Fab")
		)
		(fp_line
			(start 2.54 3.81)
			(end 2.54 -1.27)
			(stroke
				(width 0.1)
				(type default)
			)
			(layer "F.Fab")
		)
		(fp_line
			(start 0 3.81)
			(end 2.54 3.81)
			(stroke
				(width 0.1)
				(type default)
			)
			(layer "F.Fab")
		)
		(fp_poly
			(pts
				(xy -0.761746 0) (xy -2.285746 -0.762) (xy -2.285746 0.762)
			)
			(stroke
				(width 0)
				(type default)
			)
			(fill yes)
			(layer "F.Fab")
		)
		(pad "1" thru_hole circle
			(at 0 0 90)
			(size 1.0033 1.0033)
			(drill 0.249936)
			(layers "*.Cu" "*.Mask")
			(remove_unused_layers no)
			(net "TDR_DIFF_100_IN3_DN")
			(clearance 0.10795)
			(thermal_gap 0.10795)
			(padstack
				(mode front_inner_back)
				(layer "Inner"
					(shape circle)
					(size 0.8001 0.8001)
					(clearance 0.1524)
				)
				(layer "B.Cu"
					(shape circle)
					(size 1.0033 1.0033)
					(clearance 0.10795)
				)
			)
		)
		(pad "2" thru_hole circle
			(at 2.54 0 90)
			(size 1.9939 1.9939)
			(drill 0.249936)
			(layers "*.Cu" "*.Mask")
			(remove_unused_layers no)
			(net "T1_GND")
			(clearance 0.10795)
			(thermal_gap 0.10795)
			(padstack
				(mode front_inner_back)
				(layer "Inner"
					(shape circle)
					(size 0.8001 0.8001)
					(clearance 0.1524)
				)
				(layer "B.Cu"
					(shape circle)
					(size 1.9939 1.9939)
					(clearance 0.10795)
				)
			)
		)
		(pad "3" thru_hole circle
			(at 2.54 2.54 90)
			(size 1.9939 1.9939)
			(drill 0.249936)
			(layers "*.Cu" "*.Mask")
			(remove_unused_layers no)
			(net "T1_GND")
			(clearance 0.10795)
			(thermal_gap 0.10795)
			(padstack
				(mode front_inner_back)
				(layer "Inner"
					(shape circle)
					(size 0.8001 0.8001)
					(clearance 0.1524)
				)
				(layer "B.Cu"
					(shape circle)
					(size 1.9939 1.9939)
					(clearance 0.10795)
				)
			)
		)
		(pad "4" thru_hole circle
			(at 0 2.54 90)
			(size 1.0033 1.0033)
			(drill 0.249936)
			(layers "*.Cu" "*.Mask")
			(remove_unused_layers no)
			(net "TDR_DIFF_100_IN3_DP")
			(clearance 0.10795)
			(thermal_gap 0.10795)
			(padstack
				(mode front_inner_back)
				(layer "Inner"
					(shape circle)
					(size 0.8001 0.8001)
					(clearance 0.1524)
				)
				(layer "B.Cu"
					(shape circle)
					(size 1.0033 1.0033)
					(clearance 0.10795)
				)
			)
		)
	)
	(footprint ""
		(layer "F.Cu")
		(at 424.204892 -390.616948 180)
		(property "Reference" "C1754"
			(at 0 0 180)
			(layer "F.SilkS")
			(hide yes)
			(effects
				(font
					(size 1.27 1.27)
				)
			)
		)
		(property "Value" ""
			(at 0 0 180)
			(layer "F.Fab")
			(effects
				(font
					(size 1.27 1.27)
				)
			)
		)
		(duplicate_pad_numbers_are_jumpers no)
		(fp_line
			(start 0.7874 0.4064)
			(end -0.7874 0.4064)
			(stroke
				(width 0.1524)
				(type default)
			)
			(layer "F.SilkS")
		)
		(fp_line
			(start 0.7874 -0.4064)
			(end 0.7874 0.4064)
			(stroke
				(width 0.1524)
				(type default)
			)
			(layer "F.SilkS")
		)
		(fp_line
			(start -0.7874 0.4064)
			(end -0.7874 -0.4064)
			(stroke
				(width 0.1524)
				(type default)
			)
			(layer "F.SilkS")
		)
		(fp_line
			(start -0.7874 -0.4064)
			(end 0.7874 -0.4064)
			(stroke
				(width 0.1524)
				(type default)
			)
			(layer "F.SilkS")
		)
		(fp_line
			(start 0.67945 0.3048)
			(end 0.120396 0.3048)
			(stroke
				(width 0.1)
				(type default)
			)
			(layer "F.Fab")
		)
		(fp_line
			(start 0.67945 -0.3048)
			(end 0.67945 0.3048)
			(stroke
				(width 0.1)
				(type default)
			)
			(layer "F.Fab")
		)
		(fp_line
			(start 0.12065 -0.2794)
			(end 0.12065 -0.3048)
			(stroke
				(width 0.1)
				(type default)
			)
			(layer "F.Fab")
		)
		(fp_line
			(start 0.12065 -0.3048)
			(end 0.67945 -0.3048)
			(stroke
				(width 0.1)
				(type default)
			)
			(layer "F.Fab")
		)
		(fp_line
			(start 0.120396 0.3048)
			(end 0.120396 0.2794)
			(stroke
				(width 0.1)
				(type default)
			)
			(layer "F.Fab")
		)
		(fp_line
			(start 0.120396 0.2794)
			(end -0.12065 0.2794)
			(stroke
				(width 0.1)
				(type default)
			)
			(layer "F.Fab")
		)
		(fp_line
			(start -0.12065 0.3048)
			(end -0.67945 0.3048)
			(stroke
				(width 0.1)
				(type default)
			)
			(layer "F.Fab")
		)
		(fp_line
			(start -0.12065 0.2794)
			(end -0.12065 0.3048)
			(stroke
				(width 0.1)
				(type default)
			)
			(layer "F.Fab")
		)
		(fp_line
			(start -0.12065 -0.2794)
			(end 0.12065 -0.2794)
			(stroke
				(width 0.1)
				(type default)
			)
			(layer "F.Fab")
		)
		(fp_line
			(start -0.12065 -0.305054)
			(end -0.12065 -0.2794)
			(stroke
				(width 0.1)
				(type default)
			)
			(layer "F.Fab")
		)
		(fp_line
			(start -0.67945 0.3048)
			(end -0.67945 -0.305054)
			(stroke
				(width 0.1)
				(type default)
			)
			(layer "F.Fab")
		)
		(fp_line
			(start -0.67945 -0.305054)
			(end -0.12065 -0.305054)
			(stroke
				(width 0.1)
				(type default)
			)
			(layer "F.Fab")
		)
		(pad "1" smd circle
			(at -0.40005 0 180)
			(size 0 0)
			(layers "F.Cu" "F.Mask" "F.Paste")
			(net "FM_SWB_BIC_READY_ISO_N")
		)
		(pad "2" smd circle
			(at 0.40005 0 180)
			(size 0 0)
			(layers "F.Cu" "F.Mask" "F.Paste")
			(net "GND")
		)
	)
)
